(kicad_pcb
	(version 20260206)
	(generator "pcbnew")
	(generator_version "10.0")
	(general
		(thickness 1.6)
		(legacy_teardrops no)
	)
	(paper "A4")
	(title_block
		(title "timecard-production-celestica-r4006 — R4006-B0001-02_R01.brd")
		(comment 1 "Time Appliance Project (Time Card) / footprints 649-652 of 1113")
	)
	(layers
		(0 "F.Cu" signal "TOP")
		(4 "In1.Cu" signal "L02_GND1")
		(6 "In2.Cu" signal "L03_SIG1")
		(8 "In3.Cu" signal "L04_GND2")
		(10 "In4.Cu" signal "L05_VCC1")
		(12 "In5.Cu" signal "L06_VCC2")
		(14 "In6.Cu" signal "L07_GND3")
		(16 "In7.Cu" signal "L08_SIG2")
		(18 "In8.Cu" signal "L09_GND4")
		(2 "B.Cu" signal "BOTTOM")
		(9 "F.Adhes" user "F.Adhesive")
		(11 "B.Adhes" user "B.Adhesive")
		(13 "F.Paste" user "Package Geometry/Pastemask Top")
		(15 "B.Paste" user "Package Geometry/Pastemask Bottom")
		(5 "F.SilkS" user "Ref Des/Silkscreen Top")
		(7 "B.SilkS" user "Ref Des/Silkscreen Bottom")
		(1 "F.Mask" user "Board Geometry/Soldermask Top")
		(3 "B.Mask" user "Board Geometry/Soldermask Bottom")
		(17 "Dwgs.User" user "User.Drawings")
		(19 "Cmts.User" user "User.Comments")
		(21 "Eco1.User" user "User.Eco1")
		(23 "Eco2.User" user "User.Eco2")
		(25 "Edge.Cuts" user "Board Geometry/Outline")
		(27 "Margin" user)
		(31 "F.CrtYd" user "Package Geometry/Place Bound Top")
		(29 "B.CrtYd" user "Package Geometry/Place Bound Bottom")
		(35 "F.Fab" user "Ref Des/Assembly Top")
		(33 "B.Fab" user "Ref Des/Assembly Bottom")
	)
	(footprint ""
		(layer "F.Cu")
		(at 53.467 -15.621 90)
		(property "Reference" "C287"
			(at 3.556 0.42037 90)
			(unlocked yes)
			(layer "F.SilkS")
			(effects
				(font
					(size 0.7874 0.5842)
					(thickness 0.1524)
				)
			)
		)
		(property "Value" "VAL*"
			(at 0.0762 2.067306 90)
			(unlocked yes)
			(layer "F.Fab")
			(hide yes)
			(effects
				(font
					(size 0.7874 0.5842)
					(thickness 0.1524)
				)
			)
		)
		(property "Device Type" "CAPACITOR-G105-0C106-BM,10UF,2A"
			(at 0.0508 1.127506 90)
			(unlocked yes)
			(layer "F.Fab")
			(hide yes)
			(effects
				(font
					(size 0.7874 0.5842)
					(thickness 0.1524)
				)
			)
		)
		(property "User Part Number" "PARTNUM*"
			(at 0.1016 4.023106 90)
			(unlocked yes)
			(layer "Cmts.User")
			(hide yes)
			(effects
				(font
					(size 0.7874 0.5842)
					(thickness 0.1524)
				)
			)
		)
		(property "Tolerance" "TOL*"
			(at 0.0762 3.032506 90)
			(unlocked yes)
			(layer "Cmts.User")
			(hide yes)
			(effects
				(font
					(size 0.7874 0.5842)
					(thickness 0.1524)
				)
			)
		)
		(duplicate_pad_numbers_are_jumpers no)
		(fp_line
			(start 1.143 -0.5588)
			(end -1.143 -0.5588)
			(stroke
				(width 0.1)
				(type default)
			)
			(layer "F.SilkS")
		)
		(fp_line
			(start -1.143 -0.5588)
			(end -1.143 0.5588)
			(stroke
				(width 0.1)
				(type default)
			)
			(layer "F.SilkS")
		)
		(fp_line
			(start 1.143 0.5588)
			(end 1.143 -0.5588)
			(stroke
				(width 0.1)
				(type default)
			)
			(layer "F.SilkS")
		)
		(fp_line
			(start -1.143 0.5588)
			(end 1.143 0.5588)
			(stroke
				(width 0.1)
				(type default)
			)
			(layer "F.SilkS")
		)
		(fp_poly
			(pts
				(xy -1.143 0.5588) (xy 1.143 0.5588) (xy 1.143 -0.5588) (xy -1.143 -0.5588)
			)
			(stroke
				(width 0)
				(type default)
			)
			(fill no)
			(layer "F.CrtYd")
		)
		(fp_line
			(start 0.508 -0.3048)
			(end -0.508 -0.3048)
			(stroke
				(width 0.1)
				(type default)
			)
			(layer "F.Fab")
		)
		(fp_line
			(start -0.508 -0.3048)
			(end -0.508 0.3048)
			(stroke
				(width 0.1)
				(type default)
			)
			(layer "F.Fab")
		)
		(fp_line
			(start 0.508 0.3048)
			(end 0.508 -0.3048)
			(stroke
				(width 0.1)
				(type default)
			)
			(layer "F.Fab")
		)
		(fp_line
			(start -0.508 0.3048)
			(end 0.508 0.3048)
			(stroke
				(width 0.1)
				(type default)
			)
			(layer "F.Fab")
		)
		(pad "1" smd rect
			(at -0.5334 0 90)
			(size 0.7112 0.6096)
			(layers "F.Cu" "F.Mask" "F.Paste")
			(net "XP3R3V_AUX_PCIE")
		)
		(pad "2" smd rect
			(at 0.5334 0 90)
			(size 0.7112 0.6096)
			(layers "F.Cu" "F.Mask" "F.Paste")
			(net "SG")
		)
		(zone
			(layer "F.Cu")
			(hatch none 0.5)
			(connect_pads
				(clearance 0)
			)
			(min_thickness 0.25)
			(keepout
				(tracks not_allowed)
				(vias allowed)
				(pads allowed)
				(copperpour not_allowed)
				(footprints allowed)
			)
			(placement
				(enabled no)
				(sheetname "")
			)
			(fill
				(thermal_gap 0.5)
				(thermal_bridge_width 0.5)
				(island_removal_mode 0)
			)
			(polygon
				(pts
					(xy 53.7718 -15.5448) (xy 53.7718 -15.6972) (xy 53.1622 -15.6972) (xy 53.1622 -15.5448)
				)
			)
		)
		(zone
			(layer "F.Cu")
			(hatch none 0.5)
			(connect_pads
				(clearance 0)
			)
			(min_thickness 0.25)
			(keepout
				(tracks allowed)
				(vias not_allowed)
				(pads allowed)
				(copperpour not_allowed)
				(footprints allowed)
			)
			(placement
				(enabled no)
				(sheetname "")
			)
			(fill
				(thermal_gap 0.5)
				(thermal_bridge_width 0.5)
				(island_removal_mode 0)
			)
			(polygon
				(pts
					(xy 53.7718 -15.5448) (xy 53.7718 -15.6972) (xy 53.1622 -15.6972) (xy 53.1622 -15.5448)
				)
			)
		)
	)
	(footprint ""
		(layer "F.Cu")
		(at 149.098 -46.736)
		(property "Reference" "TP27"
			(at -2.4892 1.43637 0)
			(unlocked yes)
			(layer "F.SilkS")
			(effects
				(font
					(size 0.7874 0.5842)
					(thickness 0.1524)
				)
				(justify left)
			)
		)
		(property "Value" ""
			(at 0 0 0)
			(layer "F.Fab")
			(effects
				(font
					(size 1.27 1.27)
				)
			)
		)
		(property "Device Type" "TP_PIONT-TP010CT020B030_PTH-TPA"
			(at -1.341882 0.996696 0)
			(unlocked yes)
			(layer "F.Fab")
			(hide yes)
			(effects
				(font
					(size 0.7874 0.5842)
					(thickness 0.000001)
				)
				(justify left)
			)
		)
		(duplicate_pad_numbers_are_jumpers no)
		(fp_poly
			(pts
				(arc
					(start 0.889 0)
					(mid -0.889 0)
					(end 0.889 0)
				)
			)
			(stroke
				(width 0)
				(type default)
			)
			(fill no)
			(layer "B.CrtYd")
		)
		(fp_poly
			(pts
				(arc
					(start 0.889 0)
					(mid -0.889 0)
					(end 0.889 0)
				)
			)
			(stroke
				(width 0)
				(type default)
			)
			(fill no)
			(layer "F.CrtYd")
		)
		(pad "1" thru_hole circle
			(at 0 0)
			(size 0.508 0.508)
			(drill 0.254)
			(layers "*.Cu" "*.Mask")
			(remove_unused_layers no)
			(net "R_SHT3X_ALERT_N")
			(clearance 0.1016)
			(padstack
				(mode front_inner_back)
				(layer "Inner"
					(shape circle)
					(size 0.508 0.508)
					(clearance 0.1016)
				)
				(layer "B.Cu"
					(shape circle)
					(size 0.762 0.762)
					(clearance -0.0254)
				)
			)
		)
	)
	(footprint ""
		(layer "F.Cu")
		(at 13.899896 -47.099982 -90)
		(property "Reference" "U16"
			(at -0.906018 2.049526 90)
			(unlocked yes)
			(layer "F.SilkS")
			(effects
				(font
					(size 0.7874 0.5842)
					(thickness 0.1524)
				)
			)
		)
		(property "Value" ""
			(at 0 0 270)
			(layer "F.Fab")
			(effects
				(font
					(size 1.27 1.27)
				)
			)
		)
		(property "Device Type" "74HCT2G125DP_TSSOP8-G220-00055A"
			(at 0 2.413 270)
			(unlocked yes)
			(layer "F.Fab")
			(hide yes)
			(effects
				(font
					(size 0.7874 0.5842)
					(thickness 0.1524)
				)
			)
		)
		(property "User Part Number" "PARTNUM*"
			(at 0 3.6068 270)
			(unlocked yes)
			(layer "Cmts.User")
			(hide yes)
			(effects
				(font
					(size 0.7874 0.5842)
					(thickness 0.1524)
				)
			)
		)
		(duplicate_pad_numbers_are_jumpers no)
		(fp_line
			(start -2.426716 1.304036)
			(end -2.426716 -1.304036)
			(stroke
				(width 0.1)
				(type default)
			)
			(layer "F.SilkS")
		)
		(fp_line
			(start 2.426716 1.304036)
			(end -2.426716 1.304036)
			(stroke
				(width 0.1)
				(type default)
			)
			(layer "F.SilkS")
		)
		(fp_line
			(start -2.426716 -1.304036)
			(end 2.426716 -1.304036)
			(stroke
				(width 0.1)
				(type default)
			)
			(layer "F.SilkS")
		)
		(fp_line
			(start 2.426716 -1.304036)
			(end 2.426716 1.304036)
			(stroke
				(width 0.1)
				(type default)
			)
			(layer "F.SilkS")
		)
		(fp_poly
			(pts
				(arc
					(start -3.21437 -1.465326)
					(mid -3.21437 -0.703326)
					(end -3.21437 -1.465326)
				)
			)
			(stroke
				(width 0)
				(type default)
			)
			(fill yes)
			(layer "F.SilkS")
		)
		(fp_poly
			(pts
				(xy -2.680716 1.558036) (xy 2.680716 1.558036) (xy 2.680716 -1.558036) (xy -2.680716 -1.558036)
			)
			(stroke
				(width 0)
				(type default)
			)
			(fill no)
			(layer "F.CrtYd")
		)
		(fp_line
			(start -1.199896 1.050036)
			(end 1.199896 1.050036)
			(stroke
				(width 0.1)
				(type default)
			)
			(layer "F.Fab")
		)
		(fp_line
			(start 1.199896 1.050036)
			(end 1.199896 -1.050036)
			(stroke
				(width 0.1)
				(type default)
			)
			(layer "F.Fab")
		)
		(fp_line
			(start -1.199896 -1.050036)
			(end -1.199896 1.050036)
			(stroke
				(width 0.1)
				(type default)
			)
			(layer "F.Fab")
		)
		(fp_line
			(start 1.199896 -1.050036)
			(end -1.199896 -1.050036)
			(stroke
				(width 0.1)
				(type default)
			)
			(layer "F.Fab")
		)
		(fp_poly
			(pts
				(arc
					(start -1.922018 -1.721104)
					(mid -1.922018 -0.959104)
					(end -1.922018 -1.721104)
				)
			)
			(stroke
				(width 0)
				(type default)
			)
			(fill yes)
			(layer "F.Fab")
		)
		(fp_text user "5"
			(at 2.884932 1.580896 0)
			(unlocked yes)
			(layer "F.SilkS")
			(effects
				(font
					(size 0.635 0.4064)
					(thickness 0.1524)
				)
			)
		)
		(fp_text user "4"
			(at -2.957068 1.326896 0)
			(unlocked yes)
			(layer "F.SilkS")
			(effects
				(font
					(size 0.635 0.4064)
					(thickness 0.1524)
				)
			)
		)
		(fp_text user "8"
			(at 1.919732 -1.721104 0)
			(unlocked yes)
			(layer "F.SilkS")
			(effects
				(font
					(size 0.635 0.4064)
					(thickness 0.1524)
				)
			)
		)
		(fp_text user "4"
			(at -1.755648 1.326896 0)
			(unlocked yes)
			(layer "F.Fab")
			(effects
				(font
					(size 0.7874 0.5842)
					(thickness 0.1524)
				)
			)
		)
		(fp_text user "5"
			(at 2.181352 1.199896 0)
			(unlocked yes)
			(layer "F.Fab")
			(effects
				(font
					(size 0.7874 0.5842)
					(thickness 0.1524)
				)
			)
		)
		(fp_text user "8"
			(at 2.054352 -1.594104 0)
			(unlocked yes)
			(layer "F.Fab")
			(effects
				(font
					(size 0.7874 0.5842)
					(thickness 0.1524)
				)
			)
		)
		(pad "1" smd rect
			(at -1.690116 -0.749808 270)
			(size 0.9652 0.3048)
			(layers "F.Cu" "F.Mask" "F.Paste")
			(net "SMA2_SIG_OUT_BF_EN_N")
		)
		(pad "2" smd rect
			(at -1.690116 -0.249936 270)
			(size 0.9652 0.3048)
			(layers "F.Cu" "F.Mask" "F.Paste")
			(net "UNNAMED_12_74HCT2G125DPTSSOP8_9")
		)
		(pad "3" smd rect
			(at -1.690116 0.249936 270)
			(size 0.9652 0.3048)
			(layers "F.Cu" "F.Mask" "F.Paste")
			(net "BF_ANT2_IN")
		)
		(pad "4" smd rect
			(at -1.690116 0.749808 270)
			(size 0.9652 0.3048)
			(layers "F.Cu" "F.Mask" "F.Paste")
			(net "SG")
		)
		(pad "5" smd rect
			(at 1.690116 0.749808 270)
			(size 0.9652 0.3048)
			(layers "F.Cu" "F.Mask" "F.Paste")
			(net "BF_SMA2_SIG_IO_CONN")
		)
		(pad "6" smd rect
			(at 1.690116 0.249936 270)
			(size 0.9652 0.3048)
			(layers "F.Cu" "F.Mask" "F.Paste")
			(net "BF_SMA2_SIG_IO_CONN")
		)
		(pad "7" smd rect
			(at 1.690116 -0.249936 270)
			(size 0.9652 0.3048)
			(layers "F.Cu" "F.Mask" "F.Paste")
			(net "SMA2_SIG_IN_BF_EN_N")
		)
		(pad "8" smd rect
			(at 1.690116 -0.749808 270)
			(size 0.9652 0.3048)
			(layers "F.Cu" "F.Mask" "F.Paste")
			(net "XP3R3V_FPGA")
		)
	)
	(footprint ""
		(layer "F.Cu")
		(at 110.8456 -21.971 90)
		(property "Reference" "Y3"
			(at -7.02437 0.0254 0)
			(unlocked yes)
			(layer "F.SilkS")
			(effects
				(font
					(size 0.7874 0.5842)
					(thickness 0.1524)
				)
			)
		)
		(property "Value" ""
			(at 0 0 90)
			(layer "F.Fab")
			(effects
				(font
					(size 1.27 1.27)
				)
			)
		)
		(property "User Part Number" "PARTNUM*"
			(at 0 5.10667 90)
			(unlocked yes)
			(layer "Cmts.User")
			(hide yes)
			(effects
				(font
					(size 0.7874 0.5842)
					(thickness 0.1524)
				)
			)
		)
		(property "Device Type" "OSC6P_V2-A130-00003-AW"
			(at 0 3.91287 90)
			(unlocked yes)
			(layer "F.Fab")
			(hide yes)
			(effects
				(font
					(size 0.7874 0.5842)
					(thickness 0.1524)
				)
			)
		)
		(duplicate_pad_numbers_are_jumpers no)
		(fp_line
			(start 1.903984 -2.803906)
			(end 1.903984 2.803906)
			(stroke
				(width 0.1)
				(type default)
			)
			(layer "F.SilkS")
		)
		(fp_line
			(start -1.903984 -2.803906)
			(end 1.903984 -2.803906)
			(stroke
				(width 0.1)
				(type default)
			)
			(layer "F.SilkS")
		)
		(fp_line
			(start 1.903984 2.803906)
			(end -1.903984 2.803906)
			(stroke
				(width 0.1)
				(type default)
			)
			(layer "F.SilkS")
		)
		(fp_line
			(start -1.903984 2.803906)
			(end -1.903984 -2.803906)
			(stroke
				(width 0.1)
				(type default)
			)
			(layer "F.SilkS")
		)
		(fp_rect
			(start 2.157984 -3.057906)
			(end -2.157984 3.057906)
			(stroke
				(width 0)
				(type default)
			)
			(fill no)
			(layer "F.CrtYd")
		)
		(fp_line
			(start 1.649984 -2.549906)
			(end 1.649984 2.549906)
			(stroke
				(width 0.1)
				(type default)
			)
			(layer "F.Fab")
		)
		(fp_line
			(start -1.649984 -2.549906)
			(end 1.649984 -2.549906)
			(stroke
				(width 0.1)
				(type default)
			)
			(layer "F.Fab")
		)
		(fp_line
			(start 1.649984 2.549906)
			(end -1.649984 2.549906)
			(stroke
				(width 0.1)
				(type default)
			)
			(layer "F.Fab")
		)
		(fp_line
			(start -1.649984 2.549906)
			(end -1.649984 -2.549906)
			(stroke
				(width 0.1)
				(type default)
			)
			(layer "F.Fab")
		)
		(fp_text user "1"
			(at -1.69037 -3.1496 0)
			(unlocked yes)
			(layer "F.SilkS")
			(effects
				(font
					(size 0.7874 0.5842)
					(thickness 0.1524)
				)
			)
		)
		(fp_text user "3"
			(at -1.56337 3.3274 0)
			(unlocked yes)
			(layer "F.SilkS")
			(effects
				(font
					(size 0.7874 0.5842)
					(thickness 0.1524)
				)
			)
		)
		(fp_text user "6"
			(at 2.11963 -2.6416 0)
			(unlocked yes)
			(layer "F.Fab")
			(effects
				(font
					(size 0.7874 0.5842)
					(thickness 0.1524)
				)
			)
		)
		(fp_text user "1"
			(at -2.56667 -2.2606 0)
			(unlocked yes)
			(layer "F.Fab")
			(effects
				(font
					(size 0.7874 0.5842)
					(thickness 0.1524)
				)
			)
		)
		(fp_text user "3"
			(at -2.56667 2.1844 0)
			(unlocked yes)
			(layer "F.Fab")
			(effects
				(font
					(size 0.7874 0.5842)
					(thickness 0.1524)
				)
			)
		)
		(fp_text user "4"
			(at 1.49733 2.9464 0)
			(unlocked yes)
			(layer "F.Fab")
			(effects
				(font
					(size 0.7874 0.5842)
					(thickness 0.1524)
				)
			)
		)
		(pad "1" smd rect
			(at -1.050036 -1.27 90)
			(size 0.889 0.635)
			(layers "F.Cu" "F.Mask" "F.Paste")
			(net "CLK_200M_OE")
		)
		(pad "2" smd rect
			(at -1.050036 0 90)
			(size 0.889 0.635)
			(layers "F.Cu" "F.Mask" "F.Paste")
			(net "Net_763")
		)
		(pad "3" smd rect
			(at -1.050036 1.27 90)
			(size 0.889 0.635)
			(layers "F.Cu" "F.Mask" "F.Paste")
			(net "SG")
		)
		(pad "4" smd rect
			(at 1.050036 1.27 90)
			(size 0.889 0.635)
			(layers "F.Cu" "F.Mask" "F.Paste")
			(net "OSC_200M_CLKP")
		)
		(pad "5" smd rect
			(at 1.050036 0 90)
			(size 0.889 0.635)
			(layers "F.Cu" "F.Mask" "F.Paste")
			(net "OSC_200M_CLKN")
		)
		(pad "6" smd rect
			(at 1.050036 -1.27 90)
			(size 0.889 0.635)
			(layers "F.Cu" "F.Mask" "F.Paste")
			(net "VDD3V3_OSC_200M")
		)
		(zone
			(layer "F.Cu")
			(hatch none 0.5)
			(connect_pads
				(clearance 0)
			)
			(min_thickness 0.25)
			(keepout
				(tracks allowed)
				(vias not_allowed)
				(pads allowed)
				(copperpour not_allowed)
				(footprints allowed)
			)
			(placement
				(enabled no)
				(sheetname "")
			)
			(fill
				(thermal_gap 0.5)
				(thermal_bridge_width 0.5)
				(island_removal_mode 0)
			)
			(polygon
				(pts
					(xy 108.295694 -20.321016) (xy 113.395506 -20.321016) (xy 113.395506 -23.620984) (xy 108.295694 -23.620984)
				)
			)
			(polygon
				(pts
					(xy 109.8931 -21.365464) (xy 109.8931 -20.476464) (xy 109.2581 -20.476464) (xy 109.2581 -21.365464)
				)
			)
			(polygon
				(pts
					(xy 109.8931 -23.465536) (xy 109.8931 -22.576536) (xy 109.2581 -22.576536) (xy 109.2581 -23.465536)
				)
			)
			(polygon
				(pts
					(xy 111.1631 -23.465536) (xy 111.1631 -22.576536) (xy 110.5281 -22.576536) (xy 110.5281 -23.465536)
				)
			)
			(polygon
				(pts
					(xy 111.1631 -21.365464) (xy 111.1631 -20.476464) (xy 110.5281 -20.476464) (xy 110.5281 -21.365464)
				)
			)
			(polygon
				(pts
					(xy 112.4331 -21.365464) (xy 112.4331 -20.476464) (xy 111.7981 -20.476464) (xy 111.7981 -21.365464)
				)
			)
			(polygon
				(pts
					(xy 112.4331 -23.465536) (xy 112.4331 -22.576536) (xy 111.7981 -22.576536) (xy 111.7981 -23.465536)
				)
			)
		)
	)
)
